# S9S_MB_2U (Grand Teton) — schematic netlist excerpt (pin names and nets, part order shuffled) for the footprints in the layout excerpt that follows; sources: Cadence DE-HDL packaged netlist, KiCad conversion of 03242023_DA0F0TMBIJ0_F0T_Motherboard_J_brd_V01_OCP.brd

J15  SCONN288_ADR50017P130CC  SCONN288_ADR50017-P130CC IO  pkg DDR288S_1-1VXB  page 96
  VIN_BULK0  = P12V_S3_AUX_CPU0_NVDIMM
  RFU0  = TP_CHH_CPU0_DIMM1_FRU_0
  VIN_MGMT  = P3V3_AUX
  HSCL  = I3C_SPD_DDREFGH_CPU0_LVC1_SCL_6
  HSDA  = I3C_SPD_DDREFGH_CPU0_LVC1_SDA
  VSS0  = GND
  DQ0_A  = M_H_CPU0_SA_DQ<0>
  VSS1  = GND
  DQ1_A  = M_H_CPU0_SA_DQ<1>
  VSS2  = GND
  DQS0_A_T  = M_H_CPU0_SA_DQS_DP<0>
  DQS0_A_C  = M_H_CPU0_SA_DQS_DN<0>
  VSS3  = GND
  DQ4_A  = M_H_CPU0_SA_DQ<4>
  VSS4  = GND
  DQ5_A  = M_H_CPU0_SA_DQ<5>
  VSS5  = GND
  DQ8_A  = M_H_CPU0_SA_DQ<8>
  VSS6  = GND
  DQ9_A  = M_H_CPU0_SA_DQ<9>
  VSS7  = GND
  DQS1_A_T  = M_H_CPU0_SA_DQS_DP<1>
  DQS1_A_C  = M_H_CPU0_SA_DQS_DN<1>
  VSS8  = GND
  DQ12_A  = M_H_CPU0_SA_DQ<12>
  VSS9  = GND
  DQ13_A  = M_H_CPU0_SA_DQ<13>
  VSS10  = GND
  DQ16_A  = M_H_CPU0_SA_DQ<16>
  VSS11  = GND
  DQ17_A  = M_H_CPU0_SA_DQ<17>
  VSS12  = GND
  DQS2_A_T  = M_H_CPU0_SA_DQS_DP<2>
  DQS2_A_C  = M_H_CPU0_SA_DQS_DN<2>
  VSS13  = GND
  DQ20_A  = M_H_CPU0_SA_DQ<20>
  VSS14  = GND
  DQ21_A  = M_H_CPU0_SA_DQ<21>
  VSS15  = GND
  DQ24_A  = M_H_CPU0_SA_DQ<24>
  VSS16  = GND
  DQ25_A  = M_H_CPU0_SA_DQ<25>
  VSS17  = GND
  DQS3_A_T  = M_H_CPU0_SA_DQS_DP<3>
  DQS3_A_C  = M_H_CPU0_SA_DQS_DN<3>
  VSS18  = GND
  DQ28_A  = M_H_CPU0_SA_DQ<28>
  VSS19  = GND
  DQ29_A  = M_H_CPU0_SA_DQ<29>
  VSS20  = GND
  CB0_A  = M_H_CPU0_SA_CB<0>
  VSS21  = GND
  CB1_A  = M_H_CPU0_SA_CB<1>
  VSS22  = GND
  DQS4_A_T  = M_H_CPU0_SA_DQS_DP<4>
  DQS4_A_C  = M_H_CPU0_SA_DQS_DN<4>
  VSS23  = GND
  CB4_A  = M_H_CPU0_SA_CB<4>
  VSS24  = GND
  CB5_A  = M_H_CPU0_SA_CB<5>
  VSS25  = GND
  ALERT_N  = M_H_CPU0_ALERT_N
  VSS26  = GND
  CS0_A_N  = M_H_CPU0_SA_CS_N<0>
  VSS27  = GND
  CA0_A  = M_H_CPU0_SA_CA<0>
  VSS28  = GND
  CA2_A  = M_H_CPU0_SA_CA<2>
  VSS29  = GND
  CA4_A  = M_H_CPU0_SA_CA<4>
  VSS30  = GND
  CA6_A  = M_H_CPU0_SA_CA<6>
  VSS31  = GND
  PAR_A  = M_H_CPU0_SA_PAR
  VSS32  = GND
  CA0_B  = M_H_CPU0_SB_CA<0>
  VSS33  = GND
  CA2_B  = M_H_CPU0_SB_CA<2>
  VSS34  = GND
  CA4_B  = M_H_CPU0_SB_CA<4>
  VSS35  = GND
  CA6_B  = M_H_CPU0_SB_CA<6>
  VSS36  = GND
  CS0_B_N  = M_H_CPU0_SB_CS_N<0>
  VSS37  = GND
  \lbd||rsp_a_n\  = M_H_CPU0_SA_RSP<0>
  \lbs||rsp_b_n\  = M_H_CPU0_SB_RSP<0>
  VSS38  = GND
  CB4_B  = M_H_CPU0_SB_CB<4>
  VSS39  = GND
  CB5_B  = M_H_CPU0_SB_CB<5>
  VSS40  = GND
  \dqs9_b_t||tdqs9_b_t||dbi4_b_n\  = M_H_CPU0_SB_DQS_DP<9>
  \dqs9_b_c||tdqs9_b_c\  = M_H_CPU0_SB_DQS_DN<9>
  VSS41  = GND
  CB0_B  = M_H_CPU0_SB_CB<0>
  VSS42  = GND
  CB1_B  = M_H_CPU0_SB_CB<1>
  VSS43  = GND
  DQ0_B  = M_H_CPU0_SB_DQ<0>
  VSS44  = GND
  DQ1_B  = M_H_CPU0_SB_DQ<1>
  VSS45  = GND
  DQS0_B_T  = M_H_CPU0_SB_DQS_DP<0>
  DQS0_B_C  = M_H_CPU0_SB_DQS_DN<0>
  VSS46  = GND
  DQ4_B  = M_H_CPU0_SB_DQ<4>
  VSS47  = GND
  DQ5_B  = M_H_CPU0_SB_DQ<5>
  VSS48  = GND
  DQ8_B  = M_H_CPU0_SB_DQ<8>
  VSS49  = GND
  DQ9_B  = M_H_CPU0_SB_DQ<9>
  VSS50  = GND
  DQS1_B_T  = M_H_CPU0_SB_DQS_DP<1>
  DQS1_B_C  = M_H_CPU0_SB_DQS_DN<1>
  VSS51  = GND
  DQ12_B  = M_H_CPU0_SB_DQ<12>
  VSS52  = GND
  DQ13_B  = M_H_CPU0_SB_DQ<13>
  VSS53  = GND
  DQ16_B  = M_H_CPU0_SB_DQ<16>
  VSS54  = GND
  DQ17_B  = M_H_CPU0_SB_DQ<17>
  VSS55  = GND
  DQS2_B_T  = M_H_CPU0_SB_DQS_DP<2>
  DQS2_B_C  = M_H_CPU0_SB_DQS_DN<2>
  VSS56  = GND
  DQ20_B  = M_H_CPU0_SB_DQ<20>
  VSS57  = GND
  DQ21_B  = M_H_CPU0_SB_DQ<21>
  VSS58  = GND
  DQ24_B  = M_H_CPU0_SB_DQ<24>
  VSS59  = GND
  DQ25_B  = M_H_CPU0_SB_DQ<25>
  VSS60  = GND
  DQS3_B_T  = M_H_CPU0_SB_DQS_DP<3>
  DQS3_B_C  = M_H_CPU0_SB_DQS_DN<3>
  VSS61  = GND
  DQ28_B  = M_H_CPU0_SB_DQ<28>
  VSS62  = GND
  DQ29_B  = M_H_CPU0_SB_DQ<29>
  VSS63  = GND
  RFU1  = TP_CHH_CPU0_DIMM1_FRU_1
  VIN_BULK1  = P12V_S3_AUX_CPU0_NVDIMM
  VIN_BULK2  = P12V_S3_AUX_CPU0_NVDIMM
  \pwr_good||fail_n\  = PWRGD_CHH_CPU0_DIMM1
  HSA  = PD_CHH_CPU0_DIMM1_SAA
  RFU2  = TP_CHH_CPU0_DIMM1_FRU_2
  RFU3  = TP_CHH_CPU0_DIMM1_FRU_3
  VSS64  = GND
  DQ2_A  = M_H_CPU0_SA_DQ<2>
  VSS65  = GND
  DQ3_A  = M_H_CPU0_SA_DQ<3>
  VSS66  = GND
  \dqs5_a_c||tdqs5_a_c||dqs5_a_t||tdqs5_a_t\  = M_H_CPU0_SA_DQS_DN<5>
  \dqs5_a_t||tdqs5_a_t\  = M_H_CPU0_SA_DQS_DP<5>
  VSS67  = GND
  DQ6_A  = M_H_CPU0_SA_DQ<6>
  VSS68  = GND
  DQ7_A  = M_H_CPU0_SA_DQ<7>
  VSS69  = GND
  DQ10_A  = M_H_CPU0_SA_DQ<10>
  VSS70  = GND
  DQ11_A  = M_H_CPU0_SA_DQ<11>
  VSS71  = GND
  \dqs6_a_c||tdqs6_a_c||dqs6_a_t||tdqs6_a_t\  = M_H_CPU0_SA_DQS_DN<6>
  \dqs6_a_t||tdqs6_a_t\  = M_H_CPU0_SA_DQS_DP<6>
  VSS72  = GND
  DQ14_A  = M_H_CPU0_SA_DQ<14>
  VSS73  = GND
  DQ15_A  = M_H_CPU0_SA_DQ<15>
  VSS74  = GND
  DQ18_A  = M_H_CPU0_SA_DQ<18>
  VSS75  = GND
  DQ19_A  = M_H_CPU0_SA_DQ<19>
  VSS76  = GND
  \dqs7_a_c||tdqs7_a_c\  = M_H_CPU0_SA_DQS_DN<7>
  \dqs7_a_t||tdqs7_a_t\  = M_H_CPU0_SA_DQS_DP<7>
  VSS77  = GND
  DQ22_A  = M_H_CPU0_SA_DQ<22>
  VSS78  = GND
  DQ23_A  = M_H_CPU0_SA_DQ<23>
  VSS79  = GND
  DQ26_A  = M_H_CPU0_SA_DQ<26>
  VSS80  = GND
  DQ27_A  = M_H_CPU0_SA_DQ<27>
  VSS81  = GND
  \dqs8_a_c||tdqs8_a_c\  = M_H_CPU0_SA_DQS_DN<8>
  \dqs8_a_t||tdqs8_a_t\  = M_H_CPU0_SA_DQS_DP<8>
  VSS82  = GND
  DQ30_A  = M_H_CPU0_SA_DQ<30>
  VSS83  = GND
  DQ31_A  = M_H_CPU0_SA_DQ<31>
  VSS84  = GND
  CB2_A  = M_H_CPU0_SA_CB<2>
  VSS85  = GND
  CB3_A  = M_H_CPU0_SA_CB<3>
  VSS86  = GND
  \dqs9_a_c||tdqs9_a_c\  = M_H_CPU0_SA_DQS_DN<9>
  \dqs9_a_t||tdqs9_a_t\  = M_H_CPU0_SA_DQS_DP<9>
  VSS87  = GND
  CB6_A  = M_H_CPU0_SA_CB<6>
  VSS88  = GND
  CB7_A  = M_H_CPU0_SA_CB<7>
  VSS89  = GND
  RESET_N  = RST_M_GH_CPU0_FPGA_N
  VSS90  = GND
  CS1_A_N  = M_H_CPU0_SA_CS_N<1>
  VSS91  = GND
  CA1_A  = M_H_CPU0_SA_CA<1>
  VSS92  = GND
  CA3_A  = M_H_CPU0_SA_CA<3>
  VSS93  = GND
  CA5_A  = M_H_CPU0_SA_CA<5>
  VSS94  = GND
  CK_T  = M_H_CPU0_CLK_DP<0>
  CK_C  = M_H_CPU0_CLK_DN<0>
  VSS95  = GND
  RFU4  = TP_CHH_CPU0_DIMM1_FRU_4
  CA1_B  = M_H_CPU0_SB_CA<1>
  VSS96  = GND
  CA3_B  = M_H_CPU0_SB_CA<3>
  VSS97  = GND
  CA5_B  = M_H_CPU0_SB_CA<5>
  VSS98  = GND
  PAR_B  = M_H_CPU0_SB_PAR
  VSS99  = GND
  CS1_B_N  = M_H_CPU0_SB_CS_N<1>
  VSS100  = GND
  RFU5  = TP_CHH_CPU0_DIMM1_FRU_5
  RFU6  = TP_CHH_CPU0_DIMM1_FRU_6
  VSS101  = GND
  CB6_B  = M_H_CPU0_SB_CB<6>
  VSS102  = GND
  CB7_B  = M_H_CPU0_SB_CB<7>
  VSS103  = GND
  DQS4_B_C  = M_H_CPU0_SB_DQS_DN<4>
  DQS4_B_T  = M_H_CPU0_SB_DQS_DP<4>
  VSS104  = GND
  CB2_B  = M_H_CPU0_SB_CB<2>
  VSS105  = GND
  CB3_B  = M_H_CPU0_SB_CB<3>
  VSS106  = GND
  DQ2_B  = M_H_CPU0_SB_DQ<2>
  VSS107  = GND
  DQ3_B  = M_H_CPU0_SB_DQ<3>
  VSS108  = GND
  \dqs5_b_c||tdqs5_b_c\  = M_H_CPU0_SB_DQS_DN<5>
  \dqs5_b_t||tdqs5_b_t\  = M_H_CPU0_SB_DQS_DP<5>
  VSS109  = GND
  DQ6_B  = M_H_CPU0_SB_DQ<6>
  VSS110  = GND
  DQ7_B  = M_H_CPU0_SB_DQ<7>
  VSS111  = GND
  DQ10_B  = M_H_CPU0_SB_DQ<10>
  VSS112  = GND
  DQ11_B  = M_H_CPU0_SB_DQ<11>
  VSS113  = GND
  \dqs6_b_c||tdqs6_b_c\  = M_H_CPU0_SB_DQS_DN<6>
  \dqs6_b_t||tdqs6_b_t\  = M_H_CPU0_SB_DQS_DP<6>
  VSS114  = GND
  DQ14_B  = M_H_CPU0_SB_DQ<14>
  VSS115  = GND
  DQ15_B  = M_H_CPU0_SB_DQ<15>
  VSS116  = GND
  DQ18_B  = M_H_CPU0_SB_DQ<18>
  VSS117  = GND
  DQ19_B  = M_H_CPU0_SB_DQ<19>
  VSS118  = GND
  \dqs7_b_c||tdqs7_b_c\  = M_H_CPU0_SB_DQS_DN<7>
  \dqs7_b_t||tdqs7_b_t\  = M_H_CPU0_SB_DQS_DP<7>
  VSS119  = GND
  DQ22_B  = M_H_CPU0_SB_DQ<22>
  VSS120  = GND
  DQ23_B  = M_H_CPU0_SB_DQ<23>
  VSS121  = GND
  DQ26_B  = M_H_CPU0_SB_DQ<26>
  VSS122  = GND
  DQ27_B  = M_H_CPU0_SB_DQ<27>
  VSS123  = GND
  \dqs8_b_c||tdqs8_b_c\  = M_H_CPU0_SB_DQS_DN<8>
  \dqs8_b_t||tdqs8_b_t\  = M_H_CPU0_SB_DQS_DP<8>
  VSS124  = GND
  DQ30_B  = M_H_CPU0_SB_DQ<30>
  VSS125  = GND
  DQ31_B  = M_H_CPU0_SB_DQ<31>
  VSS126  = GND
  G1  = GND
  G2  = GND
  G3  = GND

(kicad_pcb
	(version 20260206)
	(generator "pcbnew")
	(generator_version "10.0")
	(general
		(thickness 1.6)
		(legacy_teardrops no)
	)
	(paper "A4")
	(title_block
		(title "03242023_DA0F0TMBIJ0_F0T_Motherboard_J_brd_V01_OCP.brd")
		(comment 1 "Grand Teton / footprint 2194 of 6105 (J15), pads 138-182 of 291")
	)
	(layers
		(0 "F.Cu" signal "TOP")
		(4 "In1.Cu" signal "GND")
		(6 "In2.Cu" signal "IN1")
		(8 "In3.Cu" signal "GND1")
		(10 "In4.Cu" signal "IN2")
		(12 "In5.Cu" signal "GND2")
		(14 "In6.Cu" signal "IN3")
		(16 "In7.Cu" signal "GND3")
		(18 "In8.Cu" signal "VCC")
		(20 "In9.Cu" signal "VCC1")
		(22 "In10.Cu" signal "GND4")
		(24 "In11.Cu" signal "IN4")
		(26 "In12.Cu" signal "GND5")
		(28 "In13.Cu" signal "IN5")
		(30 "In14.Cu" signal "GND6")
		(32 "In15.Cu" signal "IN6")
		(34 "In16.Cu" signal "GND7")
		(2 "B.Cu" signal "BOTTOM")
		(9 "F.Adhes" user "F.Adhesive")
		(11 "B.Adhes" user "B.Adhesive")
		(13 "F.Paste" user "Package Geometry/Pastemask Top")
		(15 "B.Paste" user "Package Geometry/Pastemask Bottom")
		(5 "F.SilkS" user "Ref Des/Silkscreen Top")
		(7 "B.SilkS" user "Ref Des/Silkscreen Bottom")
		(1 "F.Mask" user "Board Geometry/Soldermask Top")
		(3 "B.Mask" user "Board Geometry/Soldermask Bottom")
		(17 "Dwgs.User" user "User.Drawings")
		(19 "Cmts.User" user "User.Comments")
		(21 "Eco1.User" user "User.Eco1")
		(23 "Eco2.User" user "User.Eco2")
		(25 "Edge.Cuts" user "Board Geometry/Outline")
		(27 "Margin" user)
		(31 "F.CrtYd" user "Package Geometry/Place Bound Top")
		(29 "B.CrtYd" user "Package Geometry/Place Bound Bottom")
		(35 "F.Fab" user "Ref Des/Assembly Top")
		(33 "B.Fab" user "Ref Des/Assembly Bottom")
	)
	(footprint ""
		(layer "F.Cu")
		(at 461.609948 -258.091686)
		(property "Reference" "J15"
			(at 3.019552 -81.652872 0)
			(unlocked yes)
			(layer "F.SilkS")
			(effects
				(font
					(size 0.7874 0.5842)
					(thickness 0.1524)
				)
				(justify left)
			)
		)
		(property "Value" ""
			(at 0 0 0)
			(layer "F.Fab")
			(effects
				(font
					(size 1.27 1.27)
				)
			)
		)
		(duplicate_pad_numbers_are_jumpers no)
		(pad "138" smd rect
			(at -2.050034 58.224928 270)
			(size 0.519938 1.4986)
			(layers "F.Cu" "F.Mask" "F.Paste")
			(net "M_H_CPU0_SB_DQS_DN<3>")
		)
		(pad "139" smd rect
			(at -2.050034 59.075066 270)
			(size 0.519938 1.4986)
			(layers "F.Cu" "F.Mask" "F.Paste")
			(net "GND")
		)
		(pad "140" smd rect
			(at -2.050034 59.92495 270)
			(size 0.519938 1.4986)
			(layers "F.Cu" "F.Mask" "F.Paste")
			(net "M_H_CPU0_SB_DQ<28>")
		)
		(pad "141" smd rect
			(at -2.050034 60.775088 270)
			(size 0.519938 1.4986)
			(layers "F.Cu" "F.Mask" "F.Paste")
			(net "GND")
		)
		(pad "142" smd rect
			(at -2.050034 61.624972 270)
			(size 0.519938 1.4986)
			(layers "F.Cu" "F.Mask" "F.Paste")
			(net "M_H_CPU0_SB_DQ<29>")
		)
		(pad "143" smd rect
			(at -2.050034 62.47511 270)
			(size 0.519938 1.4986)
			(layers "F.Cu" "F.Mask" "F.Paste")
			(net "GND")
		)
		(pad "144" smd rect
			(at -2.050034 63.324994 270)
			(size 0.519938 1.4986)
			(layers "F.Cu" "F.Mask" "F.Paste")
			(net "TP_CHH_CPU0_DIMM1_FRU_1")
		)
		(pad "145" smd rect
			(at 2.050034 -63.324994 270)
			(size 0.519938 1.4986)
			(layers "F.Cu" "F.Mask" "F.Paste")
			(net "P12V_S3_AUX_CPU0_NVDIMM")
		)
		(pad "146" smd rect
			(at 2.050034 -62.47511 270)
			(size 0.519938 1.4986)
			(layers "F.Cu" "F.Mask" "F.Paste")
			(net "P12V_S3_AUX_CPU0_NVDIMM")
		)
		(pad "147" smd rect
			(at 2.050034 -61.624972 270)
			(size 0.519938 1.4986)
			(layers "F.Cu" "F.Mask" "F.Paste")
			(net "PWRGD_CHH_CPU0_DIMM1")
		)
		(pad "148" smd rect
			(at 2.050034 -60.775088 270)
			(size 0.519938 1.4986)
			(layers "F.Cu" "F.Mask" "F.Paste")
			(net "PD_CHH_CPU0_DIMM1_SAA")
		)
		(pad "149" smd rect
			(at 2.050034 -59.92495 270)
			(size 0.519938 1.4986)
			(layers "F.Cu" "F.Mask" "F.Paste")
			(net "TP_CHH_CPU0_DIMM1_FRU_2")
		)
		(pad "150" smd rect
			(at 2.050034 -59.075066 270)
			(size 0.519938 1.4986)
			(layers "F.Cu" "F.Mask" "F.Paste")
			(net "TP_CHH_CPU0_DIMM1_FRU_3")
		)
		(pad "151" smd rect
			(at 2.050034 -58.224928 270)
			(size 0.519938 1.4986)
			(layers "F.Cu" "F.Mask" "F.Paste")
			(net "GND")
		)
		(pad "152" smd rect
			(at 2.050034 -57.375044 270)
			(size 0.519938 1.4986)
			(layers "F.Cu" "F.Mask" "F.Paste")
			(net "M_H_CPU0_SA_DQ<2>")
		)
		(pad "153" smd rect
			(at 2.050034 -56.524906 270)
			(size 0.519938 1.4986)
			(layers "F.Cu" "F.Mask" "F.Paste")
			(net "GND")
		)
		(pad "154" smd rect
			(at 2.050034 -55.675022 270)
			(size 0.519938 1.4986)
			(layers "F.Cu" "F.Mask" "F.Paste")
			(net "M_H_CPU0_SA_DQ<3>")
		)
		(pad "155" smd rect
			(at 2.050034 -54.824884 270)
			(size 0.519938 1.4986)
			(layers "F.Cu" "F.Mask" "F.Paste")
			(net "GND")
		)
		(pad "156" smd rect
			(at 2.050034 -53.975 270)
			(size 0.519938 1.4986)
			(layers "F.Cu" "F.Mask" "F.Paste")
			(net "M_H_CPU0_SA_DQS_DN<5>")
		)
		(pad "157" smd rect
			(at 2.050034 -53.125116 270)
			(size 0.519938 1.4986)
			(layers "F.Cu" "F.Mask" "F.Paste")
			(net "M_H_CPU0_SA_DQS_DP<5>")
		)
		(pad "158" smd rect
			(at 2.050034 -52.274978 270)
			(size 0.519938 1.4986)
			(layers "F.Cu" "F.Mask" "F.Paste")
			(net "GND")
		)
		(pad "159" smd rect
			(at 2.050034 -51.425094 270)
			(size 0.519938 1.4986)
			(layers "F.Cu" "F.Mask" "F.Paste")
			(net "M_H_CPU0_SA_DQ<6>")
		)
		(pad "160" smd rect
			(at 2.050034 -50.574956 270)
			(size 0.519938 1.4986)
			(layers "F.Cu" "F.Mask" "F.Paste")
			(net "GND")
		)
		(pad "161" smd rect
			(at 2.050034 -49.725072 270)
			(size 0.519938 1.4986)
			(layers "F.Cu" "F.Mask" "F.Paste")
			(net "M_H_CPU0_SA_DQ<7>")
		)
		(pad "162" smd rect
			(at 2.050034 -48.874934 270)
			(size 0.519938 1.4986)
			(layers "F.Cu" "F.Mask" "F.Paste")
			(net "GND")
		)
		(pad "163" smd rect
			(at 2.050034 -48.02505 270)
			(size 0.519938 1.4986)
			(layers "F.Cu" "F.Mask" "F.Paste")
			(net "M_H_CPU0_SA_DQ<10>")
		)
		(pad "164" smd rect
			(at 2.050034 -47.174912 270)
			(size 0.519938 1.4986)
			(layers "F.Cu" "F.Mask" "F.Paste")
			(net "GND")
		)
		(pad "165" smd rect
			(at 2.050034 -46.325028 270)
			(size 0.519938 1.4986)
			(layers "F.Cu" "F.Mask" "F.Paste")
			(net "M_H_CPU0_SA_DQ<11>")
		)
		(pad "166" smd rect
			(at 2.050034 -45.47489 270)
			(size 0.519938 1.4986)
			(layers "F.Cu" "F.Mask" "F.Paste")
			(net "GND")
		)
		(pad "167" smd rect
			(at 2.050034 -44.625006 270)
			(size 0.519938 1.4986)
			(layers "F.Cu" "F.Mask" "F.Paste")
			(net "M_H_CPU0_SA_DQS_DN<6>")
		)
		(pad "168" smd rect
			(at 2.050034 -43.775122 270)
			(size 0.519938 1.4986)
			(layers "F.Cu" "F.Mask" "F.Paste")
			(net "M_H_CPU0_SA_DQS_DP<6>")
		)
		(pad "169" smd rect
			(at 2.050034 -42.924984 270)
			(size 0.519938 1.4986)
			(layers "F.Cu" "F.Mask" "F.Paste")
			(net "GND")
		)
		(pad "170" smd rect
			(at 2.050034 -42.0751 270)
			(size 0.519938 1.4986)
			(layers "F.Cu" "F.Mask" "F.Paste")
			(net "M_H_CPU0_SA_DQ<14>")
		)
		(pad "171" smd rect
			(at 2.050034 -41.224962 270)
			(size 0.519938 1.4986)
			(layers "F.Cu" "F.Mask" "F.Paste")
			(net "GND")
		)
		(pad "172" smd rect
			(at 2.050034 -40.375078 270)
			(size 0.519938 1.4986)
			(layers "F.Cu" "F.Mask" "F.Paste")
			(net "M_H_CPU0_SA_DQ<15>")
		)
		(pad "173" smd rect
			(at 2.050034 -39.52494 270)
			(size 0.519938 1.4986)
			(layers "F.Cu" "F.Mask" "F.Paste")
			(net "GND")
		)
		(pad "174" smd rect
			(at 2.050034 -38.675056 270)
			(size 0.519938 1.4986)
			(layers "F.Cu" "F.Mask" "F.Paste")
			(net "M_H_CPU0_SA_DQ<18>")
		)
		(pad "175" smd rect
			(at 2.050034 -37.824918 270)
			(size 0.519938 1.4986)
			(layers "F.Cu" "F.Mask" "F.Paste")
			(net "GND")
		)
		(pad "176" smd rect
			(at 2.050034 -36.975034 270)
			(size 0.519938 1.4986)
			(layers "F.Cu" "F.Mask" "F.Paste")
			(net "M_H_CPU0_SA_DQ<19>")
		)
		(pad "177" smd rect
			(at 2.050034 -36.124896 270)
			(size 0.519938 1.4986)
			(layers "F.Cu" "F.Mask" "F.Paste")
			(net "GND")
		)
		(pad "178" smd rect
			(at 2.050034 -35.275012 270)
			(size 0.519938 1.4986)
			(layers "F.Cu" "F.Mask" "F.Paste")
			(net "M_H_CPU0_SA_DQS_DN<7>")
		)
		(pad "179" smd rect
			(at 2.050034 -34.425128 270)
			(size 0.519938 1.4986)
			(layers "F.Cu" "F.Mask" "F.Paste")
			(net "M_H_CPU0_SA_DQS_DP<7>")
		)
		(pad "180" smd rect
			(at 2.050034 -33.57499 270)
			(size 0.519938 1.4986)
			(layers "F.Cu" "F.Mask" "F.Paste")
			(net "GND")
		)
		(pad "181" smd rect
			(at 2.050034 -32.725106 270)
			(size 0.519938 1.4986)
			(layers "F.Cu" "F.Mask" "F.Paste")
			(net "M_H_CPU0_SA_DQ<22>")
		)
		(pad "182" smd rect
			(at 2.050034 -31.874968 270)
			(size 0.519938 1.4986)
			(layers "F.Cu" "F.Mask" "F.Paste")
			(net "GND")
		)
	)
)
